# BASEBOARD_FAB2 (Tioga Pass) — schematic netlist excerpt (pin names and nets, part order shuffled) for the footprints in the layout excerpt that follows; sources: Cadence DE-HDL packaged netlist, KiCad conversion of Wiwynn_Tioga_Pass_MB.brd

EU4G3  MIC5166  IC  pkg DFN  page 221
  VREF  = VR_PVTT_ABC_VREF
  BIAS  = VR_PVTT_ABC_BIAS
  AGND  = GND
  VDDQ  = VSENSE_PVDDQ_ABC_VTT
  PG  = PWRGD_PVTT_ABC_CPU0_R
  SNS  = VR_PVTT_ABC_SNS
  EN  = FM_PVTT_ABC_EN_R
  PGND  = GND
  VTT  = PVTT_ABC
  VIN  = PVDDQ_ABC
  THPAD  = GND

C6B20  CAP  0.22UF 16V 10% X7R  pkg 0402  page 105 : A = P3E_CPU0_PE1_PCH_TXP<8> ; B = P3E_CPU0_PE1_PCH_C_TXP<8>

(kicad_pcb
	(version 20260206)
	(generator "pcbnew")
	(generator_version "10.0")
	(general
		(thickness 1.6)
		(legacy_teardrops no)
	)
	(paper "A4")
	(title_block
		(title "Wiwynn_Tioga_Pass_MB.brd")
		(comment 1 "Tioga Pass / footprints 1508-1509 of 4770")
	)
	(layers
		(0 "F.Cu" signal "TOP")
		(4 "In1.Cu" signal "L2GND")
		(6 "In2.Cu" signal "L3")
		(8 "In3.Cu" signal "L4GND")
		(10 "In4.Cu" signal "L5")
		(12 "In5.Cu" signal "L6GND")
		(14 "In6.Cu" signal "L7VCC")
		(16 "In7.Cu" signal "L8VCC")
		(18 "In8.Cu" signal "L9GND")
		(20 "In9.Cu" signal "L10")
		(22 "In10.Cu" signal "L11GND")
		(24 "In11.Cu" signal "L12")
		(26 "In12.Cu" signal "L13GND")
		(2 "B.Cu" signal "BOTTOM")
		(9 "F.Adhes" user "F.Adhesive")
		(11 "B.Adhes" user "B.Adhesive")
		(13 "F.Paste" user "Package Geometry/Pastemask Top")
		(15 "B.Paste" user "Package Geometry/Pastemask Bottom")
		(5 "F.SilkS" user "Ref Des/Silkscreen Top")
		(7 "B.SilkS" user "Ref Des/Silkscreen Bottom")
		(1 "F.Mask" user "Board Geometry/Soldermask Top")
		(3 "B.Mask" user "Board Geometry/Soldermask Bottom")
		(17 "Dwgs.User" user "User.Drawings")
		(19 "Cmts.User" user "User.Comments")
		(21 "Eco1.User" user "User.Eco1")
		(23 "Eco2.User" user "User.Eco2")
		(25 "Edge.Cuts" user "Board Geometry/Outline")
		(27 "Margin" user)
		(31 "F.CrtYd" user "Package Geometry/Place Bound Top")
		(29 "B.CrtYd" user "Package Geometry/Place Bound Bottom")
		(35 "F.Fab" user "Ref Des/Assembly Top")
		(33 "B.Fab" user "Ref Des/Assembly Bottom")
	)
	(footprint ""
		(layer "F.Cu")
		(at 332.888844 -117.35562 90)
		(property "Reference" "C6B20"
			(at -0.8382 -0.67818 90)
			(unlocked yes)
			(layer "F.SilkS")
			(effects
				(font
					(size 0.4064 0.254)
					(thickness 0.1524)
				)
				(justify left)
			)
		)
		(property "Value" ""
			(at 0 0 90)
			(layer "F.Fab")
			(effects
				(font
					(size 1.27 1.27)
				)
			)
		)
		(duplicate_pad_numbers_are_jumpers no)
		(fp_poly
			(pts
				(xy 0.3048 -0.1016) (xy 0.3048 0.9906) (xy -0.3048 0.9906) (xy -0.3048 -0.1016)
			)
			(stroke
				(width 0)
				(type default)
			)
			(fill no)
			(layer "F.CrtYd")
		)
		(fp_line
			(start 0.3048 -0.1016)
			(end -0.3048 -0.1016)
			(stroke
				(width 0.1)
				(type default)
			)
			(layer "F.Fab")
		)
		(fp_line
			(start -0.3048 -0.1016)
			(end -0.3048 0.9906)
			(stroke
				(width 0.1)
				(type default)
			)
			(layer "F.Fab")
		)
		(fp_line
			(start 0.3048 0.9906)
			(end 0.3048 -0.1016)
			(stroke
				(width 0.1)
				(type default)
			)
			(layer "F.Fab")
		)
		(fp_line
			(start -0.3048 0.9906)
			(end 0.3048 0.9906)
			(stroke
				(width 0.1)
				(type default)
			)
			(layer "F.Fab")
		)
		(pad "1" smd rect
			(at 0 0 90)
			(size 0.508 0.508)
			(layers "F.Cu" "F.Mask" "F.Paste")
			(net "P3E_CPU0_PE1_PCH_TXP<8>")
		)
		(pad "2" smd rect
			(at 0 0.889 90)
			(size 0.508 0.508)
			(layers "F.Cu" "F.Mask" "F.Paste")
			(net "P3E_CPU0_PE1_PCH_C_TXP<8>")
		)
		(zone
			(layer "F.Cu")
			(hatch none 0.5)
			(connect_pads
				(clearance 0)
			)
			(min_thickness 0.25)
			(keepout
				(tracks allowed)
				(vias not_allowed)
				(pads allowed)
				(copperpour not_allowed)
				(footprints allowed)
			)
			(placement
				(enabled no)
				(sheetname "")
			)
			(fill
				(thermal_gap 0.5)
				(thermal_bridge_width 0.5)
				(island_removal_mode 0)
			)
			(polygon
				(pts
					(xy 333.142844 -117.10162) (xy 333.142844 -117.60962) (xy 333.523844 -117.60962) (xy 333.523844 -117.10162)
				)
			)
		)
		(zone
			(layer "F.Cu")
			(hatch none 0.5)
			(connect_pads
				(clearance 0)
			)
			(min_thickness 0.25)
			(keepout
				(tracks not_allowed)
				(vias allowed)
				(pads allowed)
				(copperpour not_allowed)
				(footprints allowed)
			)
			(placement
				(enabled no)
				(sheetname "")
			)
			(fill
				(thermal_gap 0.5)
				(thermal_bridge_width 0.5)
				(island_removal_mode 0)
			)
			(polygon
				(pts
					(xy 333.523844 -117.10162) (xy 333.523844 -117.60962) (xy 333.142844 -117.60962) (xy 333.142844 -117.10162)
				)
			)
		)
	)
	(footprint ""
		(layer "F.Cu")
		(at 184.133998 -2.705608 -90)
		(property "Reference" "EU4G3"
			(at 3.086608 -1.617472 90)
			(unlocked yes)
			(layer "F.SilkS")
			(effects
				(font
					(size 0.7874 0.5842)
					(thickness 0.1524)
				)
				(justify left)
			)
		)
		(property "Value" ""
			(at 0 0 270)
			(layer "F.Fab")
			(effects
				(font
					(size 1.27 1.27)
				)
			)
		)
		(duplicate_pad_numbers_are_jumpers no)
		(fp_circle
			(center -0.835152 -0.417322)
			(end -0.835152 -0.544068)
			(stroke
				(width 0.254)
				(type default)
			)
			(fill no)
			(layer "F.SilkS")
		)
		(fp_poly
			(pts
				(xy -0.064516 -1.0922) (xy -0.064516 -0.3302) (xy 0.697484 -1.0922)
			)
			(stroke
				(width 0)
				(type default)
			)
			(fill yes)
			(layer "F.SilkS")
		)
		(fp_rect
			(start 0.597408 2.295398)
			(end 2.273808 -0.295402)
			(stroke
				(width 0)
				(type default)
			)
			(fill yes)
			(layer "F.Paste")
		)
		(fp_rect
			(start -0.064516 2.500122)
			(end 2.935478 -0.500126)
			(stroke
				(width 0)
				(type default)
			)
			(fill no)
			(layer "F.CrtYd")
		)
		(fp_line
			(start -0.064516 2.500122)
			(end -0.064516 -0.500126)
			(stroke
				(width 0.1)
				(type default)
			)
			(layer "F.Fab")
		)
		(fp_line
			(start 2.935478 2.500122)
			(end -0.064516 2.500122)
			(stroke
				(width 0.1)
				(type default)
			)
			(layer "F.Fab")
		)
		(fp_line
			(start -0.064516 -0.500126)
			(end 2.935478 -0.500126)
			(stroke
				(width 0.1)
				(type default)
			)
			(layer "F.Fab")
		)
		(fp_line
			(start 2.935478 -0.500126)
			(end 2.935478 2.500122)
			(stroke
				(width 0.1)
				(type default)
			)
			(layer "F.Fab")
		)
		(fp_circle
			(center -0.835152 -0.417322)
			(end -0.835152 -0.544068)
			(stroke
				(width 0.254)
				(type default)
			)
			(fill no)
			(layer "F.Fab")
		)
		(pad "1" smd rect
			(at 0 0 270)
			(size 0.6858 0.3048)
			(layers "F.Cu" "F.Mask" "F.Paste")
			(net "VR_PVTT_ABC_VREF")
		)
		(pad "2" smd rect
			(at 0 0.500126 270)
			(size 0.6858 0.3048)
			(layers "F.Cu" "F.Mask" "F.Paste")
			(net "VR_PVTT_ABC_BIAS")
		)
		(pad "3" smd rect
			(at 0 0.999998 270)
			(size 0.6858 0.3048)
			(layers "F.Cu" "F.Mask" "F.Paste")
			(net "GND")
		)
		(pad "4" smd rect
			(at 0 1.500124 270)
			(size 0.6858 0.3048)
			(layers "F.Cu" "F.Mask" "F.Paste")
			(net "VSENSE_PVDDQ_ABC_VTT")
		)
		(pad "5" smd rect
			(at 0 1.999996 270)
			(size 0.6858 0.3048)
			(layers "F.Cu" "F.Mask" "F.Paste")
			(net "PWRGD_PVTT_ABC_CPU0_R")
		)
		(pad "6" smd rect
			(at 2.871216 1.999996 270)
			(size 0.6858 0.3048)
			(layers "F.Cu" "F.Mask" "F.Paste")
			(net "VR_PVTT_ABC_SNS")
		)
		(pad "7" smd rect
			(at 2.871216 1.500124 270)
			(size 0.6858 0.3048)
			(layers "F.Cu" "F.Mask" "F.Paste")
			(net "FM_PVTT_ABC_EN_R")
		)
		(pad "8" smd rect
			(at 2.871216 0.999998 270)
			(size 0.6858 0.3048)
			(layers "F.Cu" "F.Mask" "F.Paste")
			(net "GND")
		)
		(pad "9" smd rect
			(at 2.871216 0.500126 270)
			(size 0.6858 0.3048)
			(layers "F.Cu" "F.Mask" "F.Paste")
			(net "PVTT_ABC")
		)
		(pad "10" smd rect
			(at 2.871216 0 270)
			(size 0.6858 0.3048)
			(layers "F.Cu" "F.Mask" "F.Paste")
			(net "PVDDQ_ABC")
		)
		(pad "11" smd rect
			(at 1.435608 0.999998 270)
			(size 1.6764 2.5908)
			(layers "F.Cu" "F.Mask" "F.Paste")
			(net "GND")
		)
	)
)
